(kicad_pcb
	(version 20260206)
	(generator "pcbnew")
	(generator_version "10.0")
	(general
		(thickness 1.6)
		(legacy_teardrops no)
	)
	(paper "A4")
	(title_block
		(title "v1-chassis-manager — T6M_CM_d_v01_1031_1645.brd")
		(comment 1 "Open CloudServer (Microsoft) / footprints 1155-1164 of 2512")
	)
	(layers
		(0 "F.Cu" signal "TOP")
		(4 "In1.Cu" signal "GND1")
		(6 "In2.Cu" signal "IN1")
		(8 "In3.Cu" signal "VCC1")
		(10 "In4.Cu" signal "VCC2")
		(12 "In5.Cu" signal "GND2")
		(14 "In6.Cu" signal "IN2")
		(16 "In7.Cu" signal "IN3")
		(18 "In8.Cu" signal "GND3")
		(2 "B.Cu" signal "BOTTOM")
		(9 "F.Adhes" user "F.Adhesive")
		(11 "B.Adhes" user "B.Adhesive")
		(13 "F.Paste" user "Package Geometry/Pastemask Top")
		(15 "B.Paste" user "Package Geometry/Pastemask Bottom")
		(5 "F.SilkS" user "Ref Des/Silkscreen Top")
		(7 "B.SilkS" user "Ref Des/Silkscreen Bottom")
		(1 "F.Mask" user "Board Geometry/Soldermask Top")
		(3 "B.Mask" user "Board Geometry/Soldermask Bottom")
		(17 "Dwgs.User" user "User.Drawings")
		(19 "Cmts.User" user "User.Comments")
		(21 "Eco1.User" user "User.Eco1")
		(23 "Eco2.User" user "User.Eco2")
		(25 "Edge.Cuts" user "Board Geometry/Outline")
		(27 "Margin" user)
		(31 "F.CrtYd" user "Package Geometry/Place Bound Top")
		(29 "B.CrtYd" user "Package Geometry/Place Bound Bottom")
		(35 "F.Fab" user "Ref Des/Assembly Top")
		(33 "B.Fab" user "Ref Des/Assembly Bottom")
	)
	(footprint ""
		(layer "F.Cu")
		(at 130.29057 -26.569416 -90)
		(property "Reference" "R1144"
			(at 5.325618 -0.028448 90)
			(unlocked yes)
			(layer "F.SilkS")
			(effects
				(font
					(size 0.7874 0.5842)
					(thickness 0.1524)
				)
				(justify left)
			)
		)
		(property "Value" ""
			(at 0 0 270)
			(layer "F.Fab")
			(effects
				(font
					(size 1.27 1.27)
				)
			)
		)
		(duplicate_pad_numbers_are_jumpers no)
		(fp_line
			(start -0.7874 0.4064)
			(end -0.7874 -0.4064)
			(stroke
				(width 0.1524)
				(type default)
			)
			(layer "F.SilkS")
		)
		(fp_line
			(start 0.7874 0.4064)
			(end -0.7874 0.4064)
			(stroke
				(width 0.1524)
				(type default)
			)
			(layer "F.SilkS")
		)
		(fp_line
			(start -0.7874 -0.4064)
			(end 0.7874 -0.4064)
			(stroke
				(width 0.1524)
				(type default)
			)
			(layer "F.SilkS")
		)
		(fp_line
			(start 0.7874 -0.4064)
			(end 0.7874 0.4064)
			(stroke
				(width 0.1524)
				(type default)
			)
			(layer "F.SilkS")
		)
		(fp_poly
			(pts
				(xy -0.508 0.2794) (xy -0.508 0.2286) (xy -0.635 0.2286) (xy -0.635 -0.254) (xy -0.5334 -0.254)
				(xy -0.5334 -0.2794) (xy 0.5334 -0.2794) (xy 0.5334 -0.254) (xy 0.635 -0.254) (xy 0.635 0.254) (xy 0.5334 0.254)
				(xy 0.5334 0.2794)
			)
			(stroke
				(width 0)
				(type default)
			)
			(fill no)
			(layer "F.CrtYd")
		)
		(pad "1" smd rect
			(at 0.40005 0 270)
			(size 0.4572 0.508)
			(layers "F.Cu" "F.Mask" "F.Paste")
			(net "P3V3_STB_NODE1")
		)
		(pad "2" smd rect
			(at -0.40005 0 270)
			(size 0.4572 0.508)
			(layers "F.Cu" "F.Mask" "F.Paste")
			(net "SIO_PIN78")
		)
	)
	(footprint ""
		(layer "F.Cu")
		(at 133.223 -51.435 90)
		(property "Reference" "R615"
			(at 16.3576 30.63367 90)
			(unlocked yes)
			(layer "F.SilkS")
			(effects
				(font
					(size 0.7874 0.5842)
					(thickness 0.1524)
				)
				(justify left)
			)
		)
		(property "Value" ""
			(at 0 0 90)
			(layer "F.Fab")
			(effects
				(font
					(size 1.27 1.27)
				)
			)
		)
		(duplicate_pad_numbers_are_jumpers no)
		(fp_line
			(start 0.7874 -0.4064)
			(end 0.7874 0.4064)
			(stroke
				(width 0.1524)
				(type default)
			)
			(layer "F.SilkS")
		)
		(fp_line
			(start -0.7874 -0.4064)
			(end 0.7874 -0.4064)
			(stroke
				(width 0.1524)
				(type default)
			)
			(layer "F.SilkS")
		)
		(fp_line
			(start 0.7874 0.4064)
			(end -0.7874 0.4064)
			(stroke
				(width 0.1524)
				(type default)
			)
			(layer "F.SilkS")
		)
		(fp_line
			(start -0.7874 0.4064)
			(end -0.7874 -0.4064)
			(stroke
				(width 0.1524)
				(type default)
			)
			(layer "F.SilkS")
		)
		(fp_poly
			(pts
				(xy -0.508 0.2794) (xy -0.508 0.2286) (xy -0.635 0.2286) (xy -0.635 -0.254) (xy -0.5334 -0.254)
				(xy -0.5334 -0.2794) (xy 0.5334 -0.2794) (xy 0.5334 -0.254) (xy 0.635 -0.254) (xy 0.635 0.254) (xy 0.5334 0.254)
				(xy 0.5334 0.2794)
			)
			(stroke
				(width 0)
				(type default)
			)
			(fill no)
			(layer "F.CrtYd")
		)
		(pad "1" smd rect
			(at 0.40005 0 90)
			(size 0.4572 0.508)
			(layers "F.Cu" "F.Mask" "F.Paste")
			(net "P5V_NODE1")
		)
		(pad "2" smd rect
			(at -0.40005 0 90)
			(size 0.4572 0.508)
			(layers "F.Cu" "F.Mask" "F.Paste")
			(net "UART_RI_P4_R_N")
		)
	)
	(footprint ""
		(layer "F.Cu")
		(at 133.766052 -154.84475 -90)
		(property "Reference" "R299"
			(at 110.763812 60.83808 90)
			(unlocked yes)
			(layer "F.SilkS")
			(effects
				(font
					(size 0.7874 0.5842)
					(thickness 0.1524)
				)
				(justify left)
			)
		)
		(property "Value" ""
			(at 0 0 270)
			(layer "F.Fab")
			(effects
				(font
					(size 1.27 1.27)
				)
			)
		)
		(duplicate_pad_numbers_are_jumpers no)
		(fp_line
			(start -0.7874 0.4064)
			(end -0.7874 -0.4064)
			(stroke
				(width 0.1524)
				(type default)
			)
			(layer "F.SilkS")
		)
		(fp_line
			(start 0.7874 0.4064)
			(end -0.7874 0.4064)
			(stroke
				(width 0.1524)
				(type default)
			)
			(layer "F.SilkS")
		)
		(fp_line
			(start -0.7874 -0.4064)
			(end 0.7874 -0.4064)
			(stroke
				(width 0.1524)
				(type default)
			)
			(layer "F.SilkS")
		)
		(fp_line
			(start 0.7874 -0.4064)
			(end 0.7874 0.4064)
			(stroke
				(width 0.1524)
				(type default)
			)
			(layer "F.SilkS")
		)
		(fp_poly
			(pts
				(xy -0.508 0.2794) (xy -0.508 0.2286) (xy -0.635 0.2286) (xy -0.635 -0.254) (xy -0.5334 -0.254)
				(xy -0.5334 -0.2794) (xy 0.5334 -0.2794) (xy 0.5334 -0.254) (xy 0.635 -0.254) (xy 0.635 0.254) (xy 0.5334 0.254)
				(xy 0.5334 0.2794)
			)
			(stroke
				(width 0)
				(type default)
			)
			(fill no)
			(layer "F.CrtYd")
		)
		(pad "1" smd rect
			(at 0.40005 0 270)
			(size 0.4572 0.508)
			(layers "F.Cu" "F.Mask" "F.Paste")
			(net "P3V3_NODE1")
		)
		(pad "2" smd rect
			(at -0.40005 0 270)
			(size 0.4572 0.508)
			(layers "F.Cu" "F.Mask" "F.Paste")
			(net "PCIE_SW_P0_ERR")
		)
	)
	(footprint ""
		(layer "F.Cu")
		(at 90.98534 -113.771426 90)
		(property "Reference" "R1257"
			(at -0.319532 -4.22148 0)
			(unlocked yes)
			(layer "F.SilkS")
			(effects
				(font
					(size 0.7874 0.5842)
					(thickness 0.1524)
				)
				(justify left)
			)
		)
		(property "Value" ""
			(at 0 0 90)
			(layer "F.Fab")
			(effects
				(font
					(size 1.27 1.27)
				)
			)
		)
		(duplicate_pad_numbers_are_jumpers no)
		(fp_line
			(start 0.7874 -0.4064)
			(end 0.7874 0.4064)
			(stroke
				(width 0.1524)
				(type default)
			)
			(layer "F.SilkS")
		)
		(fp_line
			(start -0.7874 -0.4064)
			(end 0.7874 -0.4064)
			(stroke
				(width 0.1524)
				(type default)
			)
			(layer "F.SilkS")
		)
		(fp_line
			(start 0.7874 0.4064)
			(end -0.7874 0.4064)
			(stroke
				(width 0.1524)
				(type default)
			)
			(layer "F.SilkS")
		)
		(fp_line
			(start -0.7874 0.4064)
			(end -0.7874 -0.4064)
			(stroke
				(width 0.1524)
				(type default)
			)
			(layer "F.SilkS")
		)
		(fp_poly
			(pts
				(xy -0.508 0.2794) (xy -0.508 0.2286) (xy -0.635 0.2286) (xy -0.635 -0.254) (xy -0.5334 -0.254)
				(xy -0.5334 -0.2794) (xy 0.5334 -0.2794) (xy 0.5334 -0.254) (xy 0.635 -0.254) (xy 0.635 0.254) (xy 0.5334 0.254)
				(xy 0.5334 0.2794)
			)
			(stroke
				(width 0)
				(type default)
			)
			(fill no)
			(layer "F.CrtYd")
		)
		(pad "1" smd rect
			(at 0.40005 0 90)
			(size 0.4572 0.508)
			(layers "F.Cu" "F.Mask" "F.Paste")
			(net "PORT80_LOUT6")
		)
		(pad "2" smd rect
			(at -0.40005 0 90)
			(size 0.4572 0.508)
			(layers "F.Cu" "F.Mask" "F.Paste")
			(net "N53313577")
		)
	)
	(footprint ""
		(layer "F.Cu")
		(at 157.572964 -75.126596)
		(property "Reference" "J28"
			(at -2.983738 0.467106 0)
			(unlocked yes)
			(layer "F.SilkS")
			(effects
				(font
					(size 0.7874 0.5842)
					(thickness 0.1524)
				)
				(justify left)
			)
		)
		(property "Value" ""
			(at 0 0 0)
			(layer "F.Fab")
			(effects
				(font
					(size 1.27 1.27)
				)
			)
		)
		(duplicate_pad_numbers_are_jumpers no)
		(fp_poly
			(pts
				(xy 0.2794 0.907796) (xy 0.254 0.907796) (xy 0.254 1.0414) (xy -0.254 1.0414) (xy -0.254 1.034796)
				(xy -0.254 0.933196) (xy -0.2794 0.933196) (xy -0.2794 -0.133604) (xy -0.254 -0.133604) (xy -0.254 -0.235204)
				(xy 0.254 -0.235204) (xy 0.254 -0.133604) (xy 0.2794 -0.133604)
			)
			(stroke
				(width 0)
				(type default)
			)
			(fill no)
			(layer "F.CrtYd")
		)
		(pad "1" smd custom
			(at 0 -0.000254)
			(size 0.127 0.127)
			(layers "F.Cu" "F.Mask" "F.Paste")
			(net "P1V0_NODE1")
			(options
				(clearance outline)
				(anchor circle)
			)
			(primitives
				(gr_poly
					(pts
						(xy -0.127 0.508) (xy -0.127 -0.0508) (xy -0.254 -0.0508) (xy -0.254 -0.508) (xy 0.254 -0.508)
						(xy 0.254 -0.0508) (xy 0.127 -0.0508) (xy 0.127 0.508)
					)
					(width 0)
					(fill yes)
				)
			)
		)
		(pad "2" smd rect
			(at 0 0.799846 90)
			(size 0.4572 0.508)
			(layers "F.Cu" "F.Mask" "F.Paste")
			(net "P1V0_ADJ_S")
		)
		(zone
			(layer "F.Cu")
			(hatch none 0.5)
			(connect_pads
				(clearance 0)
			)
			(min_thickness 0.25)
			(keepout
				(tracks allowed)
				(vias not_allowed)
				(pads allowed)
				(copperpour not_allowed)
				(footprints allowed)
			)
			(placement
				(enabled no)
				(sheetname "")
			)
			(fill
				(thermal_gap 0.5)
				(thermal_bridge_width 0.5)
				(island_removal_mode 0)
			)
			(polygon
				(pts
					(xy 157.268164 -74.041) (xy 157.877764 -74.041) (xy 157.877764 -75.4126) (xy 157.268164 -75.4126)
				)
			)
		)
	)
	(footprint ""
		(layer "F.Cu")
		(at 106.082084 -153.797 180)
		(property "Reference" "PR16"
			(at 2.189226 -4.682998 0)
			(unlocked yes)
			(layer "F.SilkS")
			(effects
				(font
					(size 0.635 0.4064)
					(thickness 0.1524)
				)
				(justify left)
			)
		)
		(property "Value" ""
			(at 0 0 180)
			(layer "F.Fab")
			(effects
				(font
					(size 1.27 1.27)
				)
			)
		)
		(duplicate_pad_numbers_are_jumpers no)
		(fp_line
			(start 0.7874 0.4064)
			(end -0.7874 0.4064)
			(stroke
				(width 0.1524)
				(type default)
			)
			(layer "F.SilkS")
		)
		(fp_line
			(start 0.7874 -0.4064)
			(end 0.7874 0.4064)
			(stroke
				(width 0.1524)
				(type default)
			)
			(layer "F.SilkS")
		)
		(fp_line
			(start -0.7874 0.4064)
			(end -0.7874 -0.4064)
			(stroke
				(width 0.1524)
				(type default)
			)
			(layer "F.SilkS")
		)
		(fp_line
			(start -0.7874 -0.4064)
			(end 0.7874 -0.4064)
			(stroke
				(width 0.1524)
				(type default)
			)
			(layer "F.SilkS")
		)
		(fp_poly
			(pts
				(xy -0.508 0.2794) (xy -0.508 0.2286) (xy -0.635 0.2286) (xy -0.635 -0.254) (xy -0.5334 -0.254)
				(xy -0.5334 -0.2794) (xy 0.5334 -0.2794) (xy 0.5334 -0.254) (xy 0.635 -0.254) (xy 0.635 0.254) (xy 0.5334 0.254)
				(xy 0.5334 0.2794)
			)
			(stroke
				(width 0)
				(type default)
			)
			(fill no)
			(layer "F.CrtYd")
		)
		(pad "1" smd rect
			(at 0.40005 0 180)
			(size 0.4572 0.508)
			(layers "F.Cu" "F.Mask" "F.Paste")
			(net "P1V8_STB_NODE1_FB")
		)
		(pad "2" smd rect
			(at -0.40005 0 180)
			(size 0.4572 0.508)
			(layers "F.Cu" "F.Mask" "F.Paste")
			(net "GND")
		)
	)
	(footprint ""
		(layer "F.Cu")
		(at 163.889944 -93.840808 -90)
		(property "Reference" "R522"
			(at 1.2192 4.223512 90)
			(unlocked yes)
			(layer "F.SilkS")
			(effects
				(font
					(size 0.7874 0.5842)
					(thickness 0.1524)
				)
				(justify left)
			)
		)
		(property "Value" ""
			(at 0 0 270)
			(layer "F.Fab")
			(effects
				(font
					(size 1.27 1.27)
				)
			)
		)
		(duplicate_pad_numbers_are_jumpers no)
		(fp_line
			(start -0.7874 0.4064)
			(end -0.7874 -0.4064)
			(stroke
				(width 0.1524)
				(type default)
			)
			(layer "F.SilkS")
		)
		(fp_line
			(start 0.7874 0.4064)
			(end -0.7874 0.4064)
			(stroke
				(width 0.1524)
				(type default)
			)
			(layer "F.SilkS")
		)
		(fp_line
			(start -0.7874 -0.4064)
			(end 0.7874 -0.4064)
			(stroke
				(width 0.1524)
				(type default)
			)
			(layer "F.SilkS")
		)
		(fp_line
			(start 0.7874 -0.4064)
			(end 0.7874 0.4064)
			(stroke
				(width 0.1524)
				(type default)
			)
			(layer "F.SilkS")
		)
		(fp_poly
			(pts
				(xy -0.508 0.2794) (xy -0.508 0.2286) (xy -0.635 0.2286) (xy -0.635 -0.254) (xy -0.5334 -0.254)
				(xy -0.5334 -0.2794) (xy 0.5334 -0.2794) (xy 0.5334 -0.254) (xy 0.635 -0.254) (xy 0.635 0.254) (xy 0.5334 0.254)
				(xy 0.5334 0.2794)
			)
			(stroke
				(width 0)
				(type default)
			)
			(fill no)
			(layer "F.CrtYd")
		)
		(pad "1" smd rect
			(at 0.40005 0 270)
			(size 0.4572 0.508)
			(layers "F.Cu" "F.Mask" "F.Paste")
			(net "SPI_USB_NODE1_CLK")
		)
		(pad "2" smd rect
			(at -0.40005 0 270)
			(size 0.4572 0.508)
			(layers "F.Cu" "F.Mask" "F.Paste")
			(net "SPI_USB_NODE1_CLK_R")
		)
	)
	(footprint ""
		(layer "F.Cu")
		(at 84.82076 -188.126624 90)
		(property "Reference" "C593"
			(at 4.548886 -1.908048 90)
			(unlocked yes)
			(layer "F.SilkS")
			(effects
				(font
					(size 0.7874 0.5842)
					(thickness 0.1524)
				)
				(justify left)
			)
		)
		(property "Value" ""
			(at 0 0 90)
			(layer "F.Fab")
			(effects
				(font
					(size 1.27 1.27)
				)
			)
		)
		(duplicate_pad_numbers_are_jumpers no)
		(fp_line
			(start 0.7874 -0.4064)
			(end 0.7874 0.4064)
			(stroke
				(width 0.1524)
				(type default)
			)
			(layer "F.SilkS")
		)
		(fp_line
			(start -0.7874 -0.4064)
			(end 0.7874 -0.4064)
			(stroke
				(width 0.1524)
				(type default)
			)
			(layer "F.SilkS")
		)
		(fp_line
			(start 0 0.381)
			(end 0 -0.381)
			(stroke
				(width 0.1524)
				(type default)
			)
			(layer "F.SilkS")
		)
		(fp_line
			(start 0.7874 0.4064)
			(end -0.7874 0.4064)
			(stroke
				(width 0.1524)
				(type default)
			)
			(layer "F.SilkS")
		)
		(fp_line
			(start -0.7874 0.4064)
			(end -0.7874 -0.4064)
			(stroke
				(width 0.1524)
				(type default)
			)
			(layer "F.SilkS")
		)
		(fp_poly
			(pts
				(xy -0.5334 0.254) (xy -0.635 0.254) (xy -0.635 0.2286) (xy -0.635 -0.254) (xy -0.5334 -0.254) (xy -0.5334 -0.2794)
				(xy 0.5334 -0.2794) (xy 0.5334 -0.254) (xy 0.635 -0.254) (xy 0.635 0.254) (xy 0.5334 0.254) (xy 0.5334 0.2794)
				(xy -0.508 0.2794) (xy -0.5334 0.2794)
			)
			(stroke
				(width 0)
				(type default)
			)
			(fill no)
			(layer "F.CrtYd")
		)
		(pad "1" smd rect
			(at 0.40005 0 90)
			(size 0.4572 0.508)
			(layers "F.Cu" "F.Mask" "F.Paste")
			(net "I2C_PSU2_R_SCL")
		)
		(pad "2" smd rect
			(at -0.40005 0 90)
			(size 0.4572 0.508)
			(layers "F.Cu" "F.Mask" "F.Paste")
			(net "GND")
		)
	)
	(footprint ""
		(layer "F.Cu")
		(at 77.96276 -185.205624 90)
		(property "Reference" "C695"
			(at 4.198112 -1.736598 90)
			(unlocked yes)
			(layer "F.SilkS")
			(effects
				(font
					(size 0.7874 0.5842)
					(thickness 0.1524)
				)
				(justify left)
			)
		)
		(property "Value" ""
			(at 0 0 90)
			(layer "F.Fab")
			(effects
				(font
					(size 1.27 1.27)
				)
			)
		)
		(duplicate_pad_numbers_are_jumpers no)
		(fp_line
			(start 0.7874 -0.4064)
			(end 0.7874 0.4064)
			(stroke
				(width 0.1524)
				(type default)
			)
			(layer "F.SilkS")
		)
		(fp_line
			(start -0.7874 -0.4064)
			(end 0.7874 -0.4064)
			(stroke
				(width 0.1524)
				(type default)
			)
			(layer "F.SilkS")
		)
		(fp_line
			(start 0 0.381)
			(end 0 -0.381)
			(stroke
				(width 0.1524)
				(type default)
			)
			(layer "F.SilkS")
		)
		(fp_line
			(start 0.7874 0.4064)
			(end -0.7874 0.4064)
			(stroke
				(width 0.1524)
				(type default)
			)
			(layer "F.SilkS")
		)
		(fp_line
			(start -0.7874 0.4064)
			(end -0.7874 -0.4064)
			(stroke
				(width 0.1524)
				(type default)
			)
			(layer "F.SilkS")
		)
		(fp_poly
			(pts
				(xy -0.5334 0.254) (xy -0.635 0.254) (xy -0.635 0.2286) (xy -0.635 -0.254) (xy -0.5334 -0.254) (xy -0.5334 -0.2794)
				(xy 0.5334 -0.2794) (xy 0.5334 -0.254) (xy 0.635 -0.254) (xy 0.635 0.254) (xy 0.5334 0.254) (xy 0.5334 0.2794)
				(xy -0.508 0.2794) (xy -0.5334 0.2794)
			)
			(stroke
				(width 0)
				(type default)
			)
			(fill no)
			(layer "F.CrtYd")
		)
		(pad "1" smd rect
			(at 0.40005 0 90)
			(size 0.4572 0.508)
			(layers "F.Cu" "F.Mask" "F.Paste")
			(net "UART_T4_NODE1_RXD")
		)
		(pad "2" smd rect
			(at -0.40005 0 90)
			(size 0.4572 0.508)
			(layers "F.Cu" "F.Mask" "F.Paste")
			(net "GND")
		)
	)
	(footprint ""
		(layer "F.Cu")
		(at 106.426508 -176.965102 180)
		(property "Reference" "R735"
			(at 0.545338 3.08356 0)
			(unlocked yes)
			(layer "F.SilkS")
			(effects
				(font
					(size 0.7874 0.5842)
					(thickness 0.1524)
				)
				(justify left)
			)
		)
		(property "Value" ""
			(at 0 0 180)
			(layer "F.Fab")
			(effects
				(font
					(size 1.27 1.27)
				)
			)
		)
		(duplicate_pad_numbers_are_jumpers no)
		(fp_line
			(start 0.7874 0.4064)
			(end -0.7874 0.4064)
			(stroke
				(width 0.1524)
				(type default)
			)
			(layer "F.SilkS")
		)
		(fp_line
			(start 0.7874 -0.4064)
			(end 0.7874 0.4064)
			(stroke
				(width 0.1524)
				(type default)
			)
			(layer "F.SilkS")
		)
		(fp_line
			(start -0.7874 0.4064)
			(end -0.7874 -0.4064)
			(stroke
				(width 0.1524)
				(type default)
			)
			(layer "F.SilkS")
		)
		(fp_line
			(start -0.7874 -0.4064)
			(end 0.7874 -0.4064)
			(stroke
				(width 0.1524)
				(type default)
			)
			(layer "F.SilkS")
		)
		(fp_poly
			(pts
				(xy -0.508 0.2794) (xy -0.508 0.2286) (xy -0.635 0.2286) (xy -0.635 -0.254) (xy -0.5334 -0.254)
				(xy -0.5334 -0.2794) (xy 0.5334 -0.2794) (xy 0.5334 -0.254) (xy 0.635 -0.254) (xy 0.635 0.254) (xy 0.5334 0.254)
				(xy 0.5334 0.2794)
			)
			(stroke
				(width 0)
				(type default)
			)
			(fill no)
			(layer "F.CrtYd")
		)
		(pad "1" smd rect
			(at 0.40005 0 180)
			(size 0.4572 0.508)
			(layers "F.Cu" "F.Mask" "F.Paste")
			(net "N21700943")
		)
		(pad "2" smd rect
			(at -0.40005 0 180)
			(size 0.4572 0.508)
			(layers "F.Cu" "F.Mask" "F.Paste")
			(net "P3V3_NODE1")
		)
	)
)
